# BASEBOARD_FAB2 (Tioga Pass) — schematic netlist excerpt (pin names and nets, part order shuffled) for the footprints in the layout excerpt that follows; sources: Cadence DE-HDL packaged netlist, KiCad conversion of Wiwynn_Tioga_Pass_MB.brd

EU1G2  PXM1310B  IC  pkg QFN  page 223
  BPWM1  = NC
  DNC(0)  = NC
  APWM3  = NC
  APWM2  = VR_PVDDQ_GHJ_PWM2
  APWM1  = VR_PVDDQ_GHJ_PWM1
  SDA  = SMB_VR_STBY_LVC3_SDA
  SCL  = SMB_VR_STBY_LVC3_SCL
  RESET_N  = NC
  AVRRDY  = PWRGD_PVDDQ_GHJ_R
  AVREN  = VR_PVDDQ_GHJ_VREN
  VRHOT_N  = IRQ_PVDDQ_GHJ_VRHOT_LVT3_R_N
  PINALRT_N  = NC
  MP0  = PU_VR_PVDDQ_GHJ_FAULT1
  MP1  = TP_PVDDQ_GHJ_MP1
  VCLK  = SVID_CLK_PVDDQ_GHJ
  VDIO  = SVID_VDIO_PVDDQ_GHJ
  VALRT_N  = SVID_ALERT_PVDDQ_GHJ
  MP2  = TP_PVDDQ_GHJ_MP2
  AVSEN  = VR_PVDDQ_GHJ_AVSP
  AVREF  = VSENSE_PVDDQ_GHJ_N
  AIREF1  = VR_PVDDQ_GHJ_AIREF1
  AISEN1  = ISENSE_PVDDQ_GHJ_PH1_IMON
  AIREF2  = VR_PVDDQ_GHJ_AIREF2
  AISEN2  = ISENSE_PVDDQ_GHJ_PH2_IMON
  AIREF3  = NC
  AISEN3  = NC
  GND  = GND
  DNC(1)  = NC
  BVSEN  = NC
  BVREF  = NC
  BIREF1  = NC
  BISEN1  = GND
  XADDR2  = VR_PVDDQ_GHJ_XADDR2
  BTSEN  = NC
  ATSEN  = A_TSENSE_PVDDQ_GHJ
  XADDR1  = VR_PVDDQ_GHJ_XADDR1
  VINSEN  = VR_PVDDQ_GHJ_VINSEN
  IINSEN  = VR_PVDDQ_GHJ_AIINSEN
  VDD  = VR_PVDDQ_GHJ_VDD
  VD12  = VR_PVDDQ_GHJ_VD12
  THPAD  = GND

(kicad_pcb
	(version 20260206)
	(generator "pcbnew")
	(generator_version "10.0")
	(general
		(thickness 1.6)
		(legacy_teardrops no)
	)
	(paper "A4")
	(title_block
		(title "Wiwynn_Tioga_Pass_MB.brd")
		(comment 1 "Tioga Pass / footprint 2178 of 4770 (EU1G2), pads 1-17 of 41")
	)
	(layers
		(0 "F.Cu" signal "TOP")
		(4 "In1.Cu" signal "L2GND")
		(6 "In2.Cu" signal "L3")
		(8 "In3.Cu" signal "L4GND")
		(10 "In4.Cu" signal "L5")
		(12 "In5.Cu" signal "L6GND")
		(14 "In6.Cu" signal "L7VCC")
		(16 "In7.Cu" signal "L8VCC")
		(18 "In8.Cu" signal "L9GND")
		(20 "In9.Cu" signal "L10")
		(22 "In10.Cu" signal "L11GND")
		(24 "In11.Cu" signal "L12")
		(26 "In12.Cu" signal "L13GND")
		(2 "B.Cu" signal "BOTTOM")
		(9 "F.Adhes" user "F.Adhesive")
		(11 "B.Adhes" user "B.Adhesive")
		(13 "F.Paste" user "Package Geometry/Pastemask Top")
		(15 "B.Paste" user "Package Geometry/Pastemask Bottom")
		(5 "F.SilkS" user "Ref Des/Silkscreen Top")
		(7 "B.SilkS" user "Ref Des/Silkscreen Bottom")
		(1 "F.Mask" user "Board Geometry/Soldermask Top")
		(3 "B.Mask" user "Board Geometry/Soldermask Bottom")
		(17 "Dwgs.User" user "User.Drawings")
		(19 "Cmts.User" user "User.Comments")
		(21 "Eco1.User" user "User.Eco1")
		(23 "Eco2.User" user "User.Eco2")
		(25 "Edge.Cuts" user "Board Geometry/Outline")
		(27 "Margin" user)
		(31 "F.CrtYd" user "Package Geometry/Place Bound Top")
		(29 "B.CrtYd" user "Package Geometry/Place Bound Bottom")
		(35 "F.Fab" user "Ref Des/Assembly Top")
		(33 "B.Fab" user "Ref Des/Assembly Bottom")
	)
	(footprint ""
		(layer "F.Cu")
		(at 10.033 0.24765 180)
		(property "Reference" "EU1G2"
			(at 2.4638 -3.53187 0)
			(unlocked yes)
			(layer "F.SilkS")
			(effects
				(font
					(size 0.7874 0.5842)
					(thickness 0.1524)
				)
				(justify left)
			)
		)
		(property "Value" ""
			(at 0 0 180)
			(layer "F.Fab")
			(effects
				(font
					(size 1.27 1.27)
				)
			)
		)
		(duplicate_pad_numbers_are_jumpers no)
		(pad "1" smd custom
			(at -2.4511 -1.800098 180)
			(size 0.0508 0.0508)
			(layers "F.Cu" "F.Mask" "F.Paste")
			(net "Net_285")
			(options
				(clearance outline)
				(anchor circle)
			)
			(primitives
				(gr_poly
					(pts
						(arc
							(start 0.254 -0.1016)
							(mid 0.3556 0)
							(end 0.254 0.1016)
						)
						(xy -0.3556 0.1016) (xy -0.3556 -0.1016)
					)
					(width 0)
					(fill yes)
				)
			)
		)
		(pad "2" smd custom
			(at -2.4511 -1.400048 180)
			(size 0.0508 0.0508)
			(layers "F.Cu" "F.Mask" "F.Paste")
			(net "Net_349")
			(options
				(clearance outline)
				(anchor circle)
			)
			(primitives
				(gr_poly
					(pts
						(arc
							(start 0.254 -0.1016)
							(mid 0.3556 0)
							(end 0.254 0.1016)
						)
						(xy -0.3556 0.1016) (xy -0.3556 -0.1016)
					)
					(width 0)
					(fill yes)
				)
			)
		)
		(pad "3" smd custom
			(at -2.4511 -0.999998 180)
			(size 0.0508 0.0508)
			(layers "F.Cu" "F.Mask" "F.Paste")
			(net "Net_316")
			(options
				(clearance outline)
				(anchor circle)
			)
			(primitives
				(gr_poly
					(pts
						(arc
							(start 0.254 -0.1016)
							(mid 0.3556 0)
							(end 0.254 0.1016)
						)
						(xy -0.3556 0.1016) (xy -0.3556 -0.1016)
					)
					(width 0)
					(fill yes)
				)
			)
		)
		(pad "4" smd custom
			(at -2.4511 -0.599948 180)
			(size 0.0508 0.0508)
			(layers "F.Cu" "F.Mask" "F.Paste")
			(net "VR_PVDDQ_GHJ_PWM2")
			(options
				(clearance outline)
				(anchor circle)
			)
			(primitives
				(gr_poly
					(pts
						(arc
							(start 0.254 -0.1016)
							(mid 0.3556 0)
							(end 0.254 0.1016)
						)
						(xy -0.3556 0.1016) (xy -0.3556 -0.1016)
					)
					(width 0)
					(fill yes)
				)
			)
		)
		(pad "5" smd custom
			(at -2.4511 -0.199898 180)
			(size 0.0508 0.0508)
			(layers "F.Cu" "F.Mask" "F.Paste")
			(net "VR_PVDDQ_GHJ_PWM1")
			(options
				(clearance outline)
				(anchor circle)
			)
			(primitives
				(gr_poly
					(pts
						(arc
							(start 0.254 -0.1016)
							(mid 0.3556 0)
							(end 0.254 0.1016)
						)
						(xy -0.3556 0.1016) (xy -0.3556 -0.1016)
					)
					(width 0)
					(fill yes)
				)
			)
		)
		(pad "6" smd custom
			(at -2.4511 0.199898 180)
			(size 0.0508 0.0508)
			(layers "F.Cu" "F.Mask" "F.Paste")
			(net "SMB_VR_STBY_LVC3_SDA")
			(options
				(clearance outline)
				(anchor circle)
			)
			(primitives
				(gr_poly
					(pts
						(arc
							(start 0.254 -0.1016)
							(mid 0.3556 0)
							(end 0.254 0.1016)
						)
						(xy -0.3556 0.1016) (xy -0.3556 -0.1016)
					)
					(width 0)
					(fill yes)
				)
			)
		)
		(pad "7" smd custom
			(at -2.4511 0.599948 180)
			(size 0.0508 0.0508)
			(layers "F.Cu" "F.Mask" "F.Paste")
			(net "SMB_VR_STBY_LVC3_SCL")
			(options
				(clearance outline)
				(anchor circle)
			)
			(primitives
				(gr_poly
					(pts
						(arc
							(start 0.254 -0.1016)
							(mid 0.3556 0)
							(end 0.254 0.1016)
						)
						(xy -0.3556 0.1016) (xy -0.3556 -0.1016)
					)
					(width 0)
					(fill yes)
				)
			)
		)
		(pad "8" smd custom
			(at -2.4511 0.999998 180)
			(size 0.0508 0.0508)
			(layers "F.Cu" "F.Mask" "F.Paste")
			(net "Net_286")
			(options
				(clearance outline)
				(anchor circle)
			)
			(primitives
				(gr_poly
					(pts
						(arc
							(start 0.254 -0.1016)
							(mid 0.3556 0)
							(end 0.254 0.1016)
						)
						(xy -0.3556 0.1016) (xy -0.3556 -0.1016)
					)
					(width 0)
					(fill yes)
				)
			)
		)
		(pad "9" smd custom
			(at -2.4511 1.400048 180)
			(size 0.0508 0.0508)
			(layers "F.Cu" "F.Mask" "F.Paste")
			(net "PWRGD_PVDDQ_GHJ_R")
			(options
				(clearance outline)
				(anchor circle)
			)
			(primitives
				(gr_poly
					(pts
						(arc
							(start 0.254 -0.1016)
							(mid 0.3556 0)
							(end 0.254 0.1016)
						)
						(xy -0.3556 0.1016) (xy -0.3556 -0.1016)
					)
					(width 0)
					(fill yes)
				)
			)
		)
		(pad "10" smd custom
			(at -2.4511 1.800098 180)
			(size 0.0508 0.0508)
			(layers "F.Cu" "F.Mask" "F.Paste")
			(net "VR_PVDDQ_GHJ_VREN")
			(options
				(clearance outline)
				(anchor circle)
			)
			(primitives
				(gr_poly
					(pts
						(arc
							(start 0.254 -0.1016)
							(mid 0.3556 0)
							(end 0.254 0.1016)
						)
						(xy -0.3556 0.1016) (xy -0.3556 -0.1016)
					)
					(width 0)
					(fill yes)
				)
			)
		)
		(pad "11" smd custom
			(at -1.800098 2.4511 180)
			(size 0.0508 0.0508)
			(layers "F.Cu" "F.Mask" "F.Paste")
			(net "IRQ_PVDDQ_GHJ_VRHOT_LVT3_R_N")
			(options
				(clearance outline)
				(anchor circle)
			)
			(primitives
				(gr_poly
					(pts
						(arc
							(start -0.1016 -0.254)
							(mid 0 -0.3556)
							(end 0.1016 -0.254)
						)
						(xy 0.1016 0.3556) (xy -0.1016 0.3556)
					)
					(width 0)
					(fill yes)
				)
			)
		)
		(pad "12" smd custom
			(at -1.400048 2.4511 180)
			(size 0.0508 0.0508)
			(layers "F.Cu" "F.Mask" "F.Paste")
			(net "Net_315")
			(options
				(clearance outline)
				(anchor circle)
			)
			(primitives
				(gr_poly
					(pts
						(arc
							(start -0.1016 -0.254)
							(mid 0 -0.3556)
							(end 0.1016 -0.254)
						)
						(xy 0.1016 0.3556) (xy -0.1016 0.3556)
					)
					(width 0)
					(fill yes)
				)
			)
		)
		(pad "13" smd custom
			(at -0.999998 2.4511 180)
			(size 0.0508 0.0508)
			(layers "F.Cu" "F.Mask" "F.Paste")
			(net "PU_VR_PVDDQ_GHJ_FAULT1")
			(options
				(clearance outline)
				(anchor circle)
			)
			(primitives
				(gr_poly
					(pts
						(arc
							(start -0.1016 -0.254)
							(mid 0 -0.3556)
							(end 0.1016 -0.254)
						)
						(xy 0.1016 0.3556) (xy -0.1016 0.3556)
					)
					(width 0)
					(fill yes)
				)
			)
		)
		(pad "14" smd custom
			(at -0.599948 2.4511 180)
			(size 0.0508 0.0508)
			(layers "F.Cu" "F.Mask" "F.Paste")
			(net "TP_PVDDQ_GHJ_MP1")
			(options
				(clearance outline)
				(anchor circle)
			)
			(primitives
				(gr_poly
					(pts
						(arc
							(start -0.1016 -0.254)
							(mid 0 -0.3556)
							(end 0.1016 -0.254)
						)
						(xy 0.1016 0.3556) (xy -0.1016 0.3556)
					)
					(width 0)
					(fill yes)
				)
			)
		)
		(pad "15" smd custom
			(at -0.199898 2.4511 180)
			(size 0.0508 0.0508)
			(layers "F.Cu" "F.Mask" "F.Paste")
			(net "SVID_CLK_PVDDQ_GHJ")
			(options
				(clearance outline)
				(anchor circle)
			)
			(primitives
				(gr_poly
					(pts
						(arc
							(start -0.1016 -0.254)
							(mid 0 -0.3556)
							(end 0.1016 -0.254)
						)
						(xy 0.1016 0.3556) (xy -0.1016 0.3556)
					)
					(width 0)
					(fill yes)
				)
			)
		)
		(pad "16" smd custom
			(at 0.199898 2.4511 180)
			(size 0.0508 0.0508)
			(layers "F.Cu" "F.Mask" "F.Paste")
			(net "SVID_VDIO_PVDDQ_GHJ")
			(options
				(clearance outline)
				(anchor circle)
			)
			(primitives
				(gr_poly
					(pts
						(arc
							(start -0.1016 -0.254)
							(mid 0 -0.3556)
							(end 0.1016 -0.254)
						)
						(xy 0.1016 0.3556) (xy -0.1016 0.3556)
					)
					(width 0)
					(fill yes)
				)
			)
		)
		(pad "17" smd custom
			(at 0.599948 2.4511 180)
			(size 0.0508 0.0508)
			(layers "F.Cu" "F.Mask" "F.Paste")
			(net "SVID_ALERT_PVDDQ_GHJ")
			(options
				(clearance outline)
				(anchor circle)
			)
			(primitives
				(gr_poly
					(pts
						(arc
							(start -0.1016 -0.254)
							(mid 0 -0.3556)
							(end 0.1016 -0.254)
						)
						(xy 0.1016 0.3556) (xy -0.1016 0.3556)
					)
					(width 0)
					(fill yes)
				)
			)
		)
	)
)
